G04 ================== begin FILE IDENTIFICATION RECORD ==================*
G04 Layout Name:  D:/<user>/Wistron_project/16369-sd/gbr/16369-sd.brd*
G04 Film Name:    L3VCC*
G04 File Format:  Gerber RS274X*
G04 File Origin:  Cadence Allegro 16.5-S056*
G04 Origin Date:  Wed Mar 29 13:12:54 2017*
G04 *
G04 Layer:  VIA CLASS/L3VCC*
G04 Layer:  PIN/L3VCC*
G04 Layer:  PACKAGE GEOMETRY/PWRVCC*
G04 Layer:  ETCH/L3VCC*
G04 Layer:  DRAWING FORMAT/LAYER_L3VCC*
G04 Layer:  DRAWING FORMAT/LAYER_PCB_STORY*
G04 *
G04 Offset:    (0.00 0.00)*
G04 Mirror:    No*
G04 Mode:      Negative*
G04 Rotation:  0*
G04 FullContactRelief:  No*
G04 UndefLineWidth:     6.00*
G04 ================== end FILE IDENTIFICATION RECORD ====================*
%FSLAX35Y35*MOIN*%
%IR0*IPPOS*OFA0.00000B0.00000*MIA0B0*SFA1.00000B1.00000*%
%ADD13C,.03*%
%ADD14C,.032*%
%ADD16C,.06*%
%ADD12C,.08*%
%ADD21C,.064*%
%ADD17C,.056*%
%AMMACRO25*
4,1,15,.00398,.00044,
.003999,.000208,
.004004,-.000025,
.003996,-.000258,
.00398,-.00044,
.00483,-.00129,
.004897,-.001007,
.004947,-.000721,
.004981,-.000432,
.004997,-.000141,
.004997,.000149,
.00498,.00044,
.004946,.000729,
.004895,.001015,
.00483,.00129,
.00398,.00044,
90.*
4,1,15,.00044,-.00398,
.000208,-.003999,
-.000025,-.004004,
-.000258,-.003996,
-.00044,-.00398,
-.00129,-.00483,
-.001007,-.004897,
-.000721,-.004947,
-.000432,-.004981,
-.000141,-.004997,
.000149,-.004997,
.00044,-.00498,
.000729,-.004946,
.001015,-.004895,
.00129,-.00483,
.00044,-.00398,
90.*
4,1,15,-.00398,-.00044,
-.003999,-.000208,
-.004004,.000025,
-.003996,.000258,
-.00398,.00044,
-.00483,.00129,
-.004897,.001007,
-.004947,.000721,
-.004981,.000432,
-.004997,.000141,
-.004997,-.000149,
-.00498,-.00044,
-.004946,-.000729,
-.004895,-.001015,
-.00483,-.00129,
-.00398,-.00044,
90.*
4,1,15,-.00044,.00398,
-.000208,.003999,
.000025,.004004,
.000258,.003996,
.00044,.00398,
.00129,.00483,
.001007,.004897,
.000721,.004947,
.000432,.004981,
.000141,.004997,
-.000149,.004997,
-.00044,.00498,
-.000729,.004946,
-.001015,.004895,
-.00129,.00483,
-.00044,.00398,
90.*
%
%ADD25MACRO25*%
%AMMACRO11*
4,1,15,.00398,.00044,
.003999,.000208,
.004004,-.000025,
.003996,-.000258,
.00398,-.00044,
.00483,-.00129,
.004897,-.001007,
.004947,-.000721,
.004981,-.000432,
.004997,-.000141,
.004997,.000149,
.00498,.00044,
.004946,.000729,
.004895,.001015,
.00483,.00129,
.00398,.00044,
0.0*
4,1,15,.00044,-.00398,
.000208,-.003999,
-.000025,-.004004,
-.000258,-.003996,
-.00044,-.00398,
-.00129,-.00483,
-.001007,-.004897,
-.000721,-.004947,
-.000432,-.004981,
-.000141,-.004997,
.000149,-.004997,
.00044,-.00498,
.000729,-.004946,
.001015,-.004895,
.00129,-.00483,
.00044,-.00398,
0.0*
4,1,15,-.00398,-.00044,
-.003999,-.000208,
-.004004,.000025,
-.003996,.000258,
-.00398,.00044,
-.00483,.00129,
-.004897,.001007,
-.004947,.000721,
-.004981,.000432,
-.004997,.000141,
-.004997,-.000149,
-.00498,-.00044,
-.004946,-.000729,
-.004895,-.001015,
-.00483,-.00129,
-.00398,-.00044,
0.0*
4,1,15,-.00044,.00398,
-.000208,.003999,
.000025,.004004,
.000258,.003996,
.00044,.00398,
.00129,.00483,
.001007,.004897,
.000721,.004947,
.000432,.004981,
.000141,.004997,
-.000149,.004997,
-.00044,.00498,
-.000729,.004946,
-.001015,.004895,
-.00129,.00483,
-.00044,.00398,
0.0*
%
%ADD11MACRO11*%
%AMMACRO24*
4,1,15,-.00398,.00044,
-.003999,.000208,
-.004004,-.000025,
-.003996,-.000258,
-.00398,-.00044,
-.00483,-.00129,
-.004897,-.001007,
-.004947,-.000721,
-.004981,-.000432,
-.004997,-.000141,
-.004997,.000149,
-.00498,.00044,
-.004946,.000729,
-.004895,.001015,
-.00483,.00129,
-.00398,.00044,
0.0*
4,1,15,-.00044,-.00398,
-.000208,-.003999,
.000025,-.004004,
.000258,-.003996,
.00044,-.00398,
.00129,-.00483,
.001007,-.004897,
.000721,-.004947,
.000432,-.004981,
.000141,-.004997,
-.000149,-.004997,
-.00044,-.00498,
-.000729,-.004946,
-.001015,-.004895,
-.00129,-.00483,
-.00044,-.00398,
0.0*
4,1,15,.00398,-.00044,
.003999,-.000208,
.004004,.000025,
.003996,.000258,
.00398,.00044,
.00483,.00129,
.004897,.001007,
.004947,.000721,
.004981,.000432,
.004997,.000141,
.004997,-.000149,
.00498,-.00044,
.004946,-.000729,
.004895,-.001015,
.00483,-.00129,
.00398,-.00044,
0.0*
4,1,15,.00044,.00398,
.000208,.003999,
-.000025,.004004,
-.000258,.003996,
-.00044,.00398,
-.00129,.00483,
-.001007,.004897,
-.000721,.004947,
-.000432,.004981,
-.000141,.004997,
.000149,.004997,
.00044,.00498,
.000729,.004946,
.001015,.004895,
.00129,.00483,
.00044,.00398,
0.0*
%
%ADD24MACRO24*%
%ADD10C,.114*%
%ADD19C,.119*%
%ADD23C,.264*%
%AMMACRO20*
4,1,15,.00398,.00044,
.003999,.000208,
.004004,-.000025,
.003996,-.000258,
.00398,-.00044,
.00483,-.00129,
.004897,-.001007,
.004947,-.000721,
.004981,-.000432,
.004997,-.000141,
.004997,.000149,
.00498,.00044,
.004946,.000729,
.004895,.001015,
.00483,.00129,
.00398,.00044,
270.*
4,1,15,.00044,-.00398,
.000208,-.003999,
-.000025,-.004004,
-.000258,-.003996,
-.00044,-.00398,
-.00129,-.00483,
-.001007,-.004897,
-.000721,-.004947,
-.000432,-.004981,
-.000141,-.004997,
.000149,-.004997,
.00044,-.00498,
.000729,-.004946,
.001015,-.004895,
.00129,-.00483,
.00044,-.00398,
270.*
4,1,15,-.00398,-.00044,
-.003999,-.000208,
-.004004,.000025,
-.003996,.000258,
-.00398,.00044,
-.00483,.00129,
-.004897,.001007,
-.004947,.000721,
-.004981,.000432,
-.004997,.000141,
-.004997,-.000149,
-.00498,-.00044,
-.004946,-.000729,
-.004895,-.001015,
-.00483,-.00129,
-.00398,-.00044,
270.*
4,1,15,-.00044,.00398,
-.000208,.003999,
.000025,.004004,
.000258,.003996,
.00044,.00398,
.00129,.00483,
.001007,.004897,
.000721,.004947,
.000432,.004981,
.000141,.004997,
-.000149,.004997,
-.00044,.00498,
-.000729,.004946,
-.001015,.004895,
-.00129,.00483,
-.00044,.00398,
270.*
%
%ADD20MACRO20*%
%AMMACRO15*
4,1,15,.00398,.00044,
.003999,.000208,
.004004,-.000025,
.003996,-.000258,
.00398,-.00044,
.00483,-.00129,
.004897,-.001007,
.004947,-.000721,
.004981,-.000432,
.004997,-.000141,
.004997,.000149,
.00498,.00044,
.004946,.000729,
.004895,.001015,
.00483,.00129,
.00398,.00044,
180.*
4,1,15,.00044,-.00398,
.000208,-.003999,
-.000025,-.004004,
-.000258,-.003996,
-.00044,-.00398,
-.00129,-.00483,
-.001007,-.004897,
-.000721,-.004947,
-.000432,-.004981,
-.000141,-.004997,
.000149,-.004997,
.00044,-.00498,
.000729,-.004946,
.001015,-.004895,
.00129,-.00483,
.00044,-.00398,
180.*
4,1,15,-.00398,-.00044,
-.003999,-.000208,
-.004004,.000025,
-.003996,.000258,
-.00398,.00044,
-.00483,.00129,
-.004897,.001007,
-.004947,.000721,
-.004981,.000432,
-.004997,.000141,
-.004997,-.000149,
-.00498,-.00044,
-.004946,-.000729,
-.004895,-.001015,
-.00483,-.00129,
-.00398,-.00044,
180.*
4,1,15,-.00044,.00398,
-.000208,.003999,
.000025,.004004,
.000258,.003996,
.00044,.00398,
.00129,.00483,
.001007,.004897,
.000721,.004947,
.000432,.004981,
.000141,.004997,
-.000149,.004997,
-.00044,.00498,
-.000729,.004946,
-.001015,.004895,
-.00129,.00483,
-.00044,.00398,
180.*
%
%ADD15MACRO15*%
%AMMACRO22*
4,1,13,.02404,.0099,
.025394,.005575,
.025976,.001081,
.025769,-.003446,
.024779,-.007869,
.02404,-.0099,
.02782,-.01368,
.029773,-.008641,
.030821,-.00334,
.030933,.002063,
.030105,.007403,
.028362,.012518,
.02782,.01368,
.02404,.0099,
0.0*
4,1,13,.0099,-.02404,
.005575,-.025394,
.001081,-.025976,
-.003446,-.025769,
-.007869,-.024779,
-.0099,-.02404,
-.01368,-.02782,
-.008641,-.029773,
-.00334,-.030821,
.002063,-.030933,
.007403,-.030105,
.012518,-.028362,
.01368,-.02782,
.0099,-.02404,
0.0*
4,1,13,-.02404,-.0099,
-.025394,-.005575,
-.025976,-.001081,
-.025769,.003446,
-.024779,.007869,
-.02404,.0099,
-.02782,.01368,
-.029773,.008641,
-.030821,.00334,
-.030933,-.002063,
-.030105,-.007403,
-.028362,-.012518,
-.02782,-.01368,
-.02404,-.0099,
0.0*
4,1,13,-.0099,.02404,
-.005575,.025394,
-.001081,.025976,
.003446,.025769,
.007869,.024779,
.0099,.02404,
.01368,.02782,
.008641,.029773,
.00334,.030821,
-.002063,.030933,
-.007403,.030105,
-.012518,.028362,
-.01368,.02782,
-.0099,.02404,
0.0*
%
%ADD22MACRO22*%
%AMMACRO18*
4,1,19,.02172,.00757,
.022123,.006294,
.022452,.004997,
.022705,.003683,
.02288,.002357,
.022979,.001023,
.022999,-.000315,
.022942,-.001652,
.022807,-.002983,
.022595,-.004304,
.022307,-.005611,
.021943,-.006898,
.02172,-.00757,
.02556,-.01142,
.027155,-.006808,
.027924,-.001989,
.027846,.00289,
.026921,.007681,
.02556,.01142,
.02172,.00757,
90.*
4,1,19,.00757,-.02172,
.006294,-.022123,
.004997,-.022452,
.003683,-.022705,
.002357,-.02288,
.001023,-.022979,
-.000315,-.022999,
-.001652,-.022942,
-.002983,-.022807,
-.004304,-.022595,
-.005611,-.022307,
-.006898,-.021943,
-.00757,-.02172,
-.01142,-.02556,
-.006808,-.027155,
-.001989,-.027924,
.00289,-.027846,
.007681,-.026921,
.01142,-.02556,
.00757,-.02172,
90.*
4,1,19,-.02172,-.00757,
-.022123,-.006294,
-.022452,-.004997,
-.022705,-.003683,
-.02288,-.002357,
-.022979,-.001023,
-.022999,.000315,
-.022942,.001652,
-.022807,.002983,
-.022595,.004304,
-.022307,.005611,
-.021943,.006898,
-.02172,.00757,
-.02556,.01142,
-.027155,.006808,
-.027924,.001989,
-.027846,-.00289,
-.026921,-.007681,
-.02556,-.01142,
-.02172,-.00757,
90.*
4,1,19,-.00757,.02172,
-.006294,.022123,
-.004997,.022452,
-.003683,.022705,
-.002357,.02288,
-.001023,.022979,
.000315,.022999,
.001652,.022942,
.002983,.022807,
.004304,.022595,
.005611,.022307,
.006898,.021943,
.00757,.02172,
.01142,.02556,
.006808,.027155,
.001989,.027924,
-.00289,.027846,
-.007681,.026921,
-.01142,.02556,
-.00757,.02172,
90.*
%
%ADD18MACRO18*%
%ADD26C,.02*%
%ADD27C,.006*%
%ADD28C,.11004*%
%ADD29C,.36204*%
G75*
%LPD*%
G75*
G36*
G01X-17811Y-32378D02*
X246551D01*
Y360331D01*
X-17811D01*
Y-32378D01*
G37*
%LPC*%
G75*
G36*
G01X3004Y350394D02*
G02X3937Y351327I933J0D01*
G01X60630D01*
G02X61563Y350394I0J-933D01*
G01Y288450D01*
X17665D01*
X6595Y277380D01*
Y243828D01*
X10280Y240143D01*
X18509D01*
X21183Y242817D01*
Y252589D01*
X15969Y257803D01*
Y267980D01*
X19520Y271531D01*
X45552D01*
X52850Y264233D01*
Y207350D01*
X45889D01*
X38750Y200211D01*
Y141311D01*
X20750Y123311D01*
Y118689D01*
X24250Y115189D01*
Y76189D01*
X39250Y61189D01*
Y50189D01*
X41689Y47750D01*
X45115D01*
X53750Y39216D01*
Y24189D01*
X56689Y21250D01*
X74189D01*
X82789Y12650D01*
X119211D01*
X122750Y16189D01*
Y17189D01*
X123311Y17750D01*
X127689D01*
X130689Y14750D01*
X135311D01*
X138111Y17550D01*
X211111D01*
X225850Y32289D01*
Y142211D01*
X218251Y149810D01*
Y153690D01*
X225850Y161289D01*
Y184511D01*
X224861Y185500D01*
X233550Y194189D01*
Y208157D01*
G02X234129Y208514I400J0D01*
G01X237031Y207063D01*
G02X237547Y206229I-417J-835D01*
G01Y187472D01*
G02X237031Y186638I-933J1D01*
G01X233511Y184878D01*
G03X229673Y178670I3103J-6209D01*
G01Y-22441D01*
G02X228740Y-23374I-933J0D01*
G01X204638D01*
Y-787D01*
G03X199666Y4185I-4973J-1D01*
G01X195093D01*
G02X194697Y4636I1J400D01*
G03X187155I-3771J482D01*
G02X186759Y4185I-397J-51D01*
G01X45919D01*
G02X45523Y4636I1J400D01*
G03X37981I-3771J482D01*
G02X37585Y4185I-397J-51D01*
G01X33011D01*
G03X28039Y-787I1J-4973D01*
G01Y-23374D01*
X3937D01*
G02X3004Y-22441I0J933D01*
G01Y178265D01*
G03X-1742Y184850I-6941J0D01*
G01X-8169Y186992D01*
G02X-8807Y187877I295J885D01*
G01Y205824D01*
G02X-8169Y206709I933J0D01*
G01X-1742Y208851D01*
G03X3004Y215436I-2195J6585D01*
G01Y350394D01*
G37*
G36*
G01X83411Y14150D02*
X74811Y22750D01*
X57311D01*
X55250Y24811D01*
Y39842D01*
X45731Y49250D01*
X42311D01*
X40750Y50811D01*
Y61811D01*
X25750Y76811D01*
Y115811D01*
X22250Y119311D01*
Y122689D01*
X40250Y140689D01*
Y171368D01*
G03Y175088I-2967J1860D01*
G01Y199589D01*
X46511Y205850D01*
X52850D01*
Y117989D01*
X81950Y88889D01*
Y69411D01*
X78950Y66411D01*
Y59089D01*
X100550Y37489D01*
Y15311D01*
X99389Y14150D01*
X83411D01*
G37*
G36*
G01X171114Y350394D02*
G02X172047Y351327I933J0D01*
G01X228740D01*
G02X229673Y350394I0J-933D01*
G01Y290350D01*
X215289D01*
X211643Y286704D01*
X191745D01*
X187475Y282434D01*
Y277078D01*
X189617Y274936D01*
X205045D01*
X212550Y267431D01*
Y242898D01*
G03X212770Y242368I750J1D01*
G01X220250Y234887D01*
Y201511D01*
X197550Y178811D01*
Y171011D01*
X195350Y168811D01*
Y113311D01*
X169250Y87211D01*
Y77311D01*
X142389Y50450D01*
X111911D01*
X94650Y67711D01*
Y95711D01*
X64050Y126311D01*
Y131131D01*
G02X64733Y131413I400J-1D01*
G01X92786Y103360D01*
G03X97693Y101327I4908J4908D01*
G01X134984D01*
G03X139891Y103360I-1J6941D01*
G01X169081Y132550D01*
G03X171114Y137457I-4908J4908D01*
G01Y249131D01*
G03X166368Y255716I-6941J0D01*
G01X159941Y257858D01*
G02X159303Y258743I295J885D01*
G01Y276690D01*
G02X159941Y277575I933J0D01*
G01X166368Y279717D01*
G03X171114Y286302I-2195J6585D01*
G01Y350394D01*
G37*
G36*
G01X61563Y249131D02*
Y137457D01*
G03X62550Y133891I6941J1D01*
G01Y125689D01*
X93150Y95089D01*
Y67089D01*
X110850Y49389D01*
Y15911D01*
X109089Y14150D01*
X103211D01*
X102050Y15311D01*
Y38111D01*
X80450Y59711D01*
Y65789D01*
X83450Y68789D01*
Y89511D01*
X54350Y118611D01*
Y264855D01*
X46174Y273031D01*
X18898D01*
X14469Y268602D01*
Y257181D01*
X19683Y251967D01*
Y243439D01*
X17887Y241643D01*
X10902D01*
X8095Y244450D01*
Y276758D01*
X18287Y286950D01*
X61563D01*
Y286302D01*
G03X66309Y279717I6941J0D01*
G01X72736Y277575D01*
G02X73374Y276690I-295J-885D01*
G01Y258743D01*
G02X72736Y257858I-933J0D01*
G01X66309Y255716D01*
G03X61563Y249131I2195J-6585D01*
G37*
G36*
G01X134689Y16250D02*
X131311D01*
X128311Y19250D01*
X123835D01*
X122750Y20335D01*
Y27689D01*
X128811Y33750D01*
X150911D01*
X188250Y71089D01*
Y82189D01*
X213250Y107189D01*
Y133811D01*
X208751Y138310D01*
Y158690D01*
X213250Y163189D01*
Y176889D01*
X221411Y185050D01*
X223189D01*
X224350Y183889D01*
Y161911D01*
X216751Y154312D01*
Y149812D01*
X216750Y149811D01*
Y149189D01*
X224350Y141589D01*
Y32911D01*
X210489Y19050D01*
X137489D01*
X134689Y16250D01*
G37*
G36*
G01X215911Y288850D02*
X229673D01*
Y215031D01*
G03X232050Y209803I6941J1D01*
G01Y194811D01*
X223789Y186550D01*
X220789D01*
X211750Y177511D01*
Y163811D01*
X207251Y159312D01*
Y138312D01*
X207250Y138311D01*
Y137689D01*
X211750Y133189D01*
Y107811D01*
X186750Y82811D01*
Y71711D01*
X150289Y35250D01*
X128189D01*
X121250Y28311D01*
Y16811D01*
X118589Y14150D01*
X114111D01*
X112350Y15911D01*
Y48950D01*
X143011D01*
X170750Y76689D01*
Y86589D01*
X196850Y112689D01*
Y168189D01*
X199050Y170389D01*
Y178189D01*
X221750Y200889D01*
Y235509D01*
X214050Y243209D01*
Y267742D01*
G03X213830Y268272I-750J-1D01*
G01X205667Y276436D01*
X190239D01*
X188975Y277700D01*
Y281812D01*
X192367Y285204D01*
X212265D01*
X215911Y288850D01*
G37*
%LPD*%
G75*
G54D28*
X13800Y60400D03*
X218800Y337200D03*
G54D29*
X116339Y78740D03*
G54D13*
X48000Y38000D03*
X58700Y55600D03*
X57450Y35400D03*
X55500Y42000D03*
X69446Y48262D03*
X70360Y25750D03*
X50100Y34500D03*
X68838Y12300D03*
X39400Y41000D03*
X36900Y17600D03*
X26000Y51600D03*
X19763Y92200D03*
X55700Y121400D03*
X32100Y114900D03*
X42500Y115000D03*
X47300Y107940D03*
X34900Y106742D03*
X37100Y73960D03*
X37500Y87300D03*
X23093Y99967D03*
X9000Y81250D03*
Y77250D03*
X40900Y88400D03*
X46200Y111200D03*
X15857Y202417D03*
X47300Y168700D03*
X16253Y180320D03*
X20539Y163381D03*
X9581Y160069D03*
X11840Y177692D03*
X17100Y278300D03*
X13650Y278350D03*
X26270Y282547D03*
X22820Y282597D03*
X99300Y25700D03*
X136439Y31761D03*
X132500Y41200D03*
X79000Y43600D03*
X75100Y63900D03*
X118100Y45000D03*
X104900Y21400D03*
X114900Y39900D03*
X97200Y44150D03*
X119200Y30900D03*
X76900Y15500D03*
X73838Y12100D03*
X126742Y15658D03*
X82200Y60800D03*
X100100Y56300D03*
X125700Y26500D03*
X75600Y87000D03*
Y91500D03*
X204340Y71660D03*
X222500Y35100D03*
X169750Y62500D03*
X163452Y32350D03*
X161300Y51500D03*
X174300Y52000D03*
X172800Y44950D03*
X182800Y46500D03*
X220732Y46039D03*
X194560Y53277D03*
X160800Y72000D03*
X154444Y72036D03*
X208900Y59000D03*
X160794Y86162D03*
X219000Y104060D03*
X211000Y140500D03*
X174600Y86980D03*
X198100Y104000D03*
X218350Y111900D03*
X204818Y118400D03*
X210276Y122000D03*
X192500Y73385D03*
X193500Y135835D03*
X190900Y112200D03*
X159711Y82091D03*
X156891Y79378D03*
X184900Y106300D03*
X171263Y92837D03*
X224000Y210584D03*
X207750Y224016D03*
X220200Y151000D03*
X219269Y216635D03*
X214401Y281884D03*
X215411Y270499D03*
X209506Y229990D03*
X215916Y232222D03*
G54D14*
X42600Y129000D03*
X51500Y187600D03*
X51400Y195600D03*
X56755Y199384D03*
X212287Y39469D03*
X202783Y128937D03*
X215400Y88900D03*
X219150Y178000D03*
X222450Y199500D03*
X218700Y193900D03*
G54D16*
X37283Y173228D03*
X27283D03*
X193583D03*
X183583D03*
G54D12*
X41752Y5118D03*
X190926D03*
G54D21*
X22440Y303149D03*
X32283D03*
X22440Y322835D03*
X32283D03*
X42126D03*
X182677Y303149D03*
X192520D03*
X182677Y322835D03*
X192520D03*
X202363D03*
G54D17*
X38189Y220472D03*
Y251968D03*
Y244094D03*
Y236220D03*
Y228346D03*
X28346Y232283D03*
Y240157D03*
Y250000D03*
X12598Y312992D03*
X51968D03*
X198426Y220472D03*
Y251968D03*
Y244094D03*
Y236220D03*
Y228346D03*
X188583Y232283D03*
Y240157D03*
Y250000D03*
X172835Y312992D03*
X212205D03*
G54D25*
X214119Y216661D03*
G54D11*
X6000Y-17500D03*
X16090Y-6960D03*
Y-3360D03*
X4100Y12300D03*
X4300Y38700D03*
X21000Y53500D03*
X4629Y64843D03*
X16090Y240D03*
X63938Y11580D03*
X16090Y3840D03*
X33200Y59100D03*
X35744Y51944D03*
X41000Y36900D03*
X50100Y20700D03*
X73000Y57200D03*
X57400Y26400D03*
X63300Y37300D03*
X43900Y59600D03*
X42300Y51900D03*
X70600Y122500D03*
X65600Y128100D03*
X22383Y128937D03*
X20200Y116600D03*
X17700Y89400D03*
X50400Y118300D03*
X24000Y120900D03*
X27200Y104100D03*
X33100Y73900D03*
X32200Y91400D03*
X40000Y77100D03*
X6220Y219509D03*
X26700Y189160D03*
X51076Y202657D03*
X51500Y191500D03*
X44100Y154167D03*
X51400Y168300D03*
X56400Y158800D03*
X4100Y294900D03*
X60300Y290000D03*
X5244Y259114D03*
X4333Y242011D03*
X16977Y244294D03*
X16984Y248748D03*
X55200Y285022D03*
X18600Y338800D03*
X4200Y312100D03*
Y329000D03*
X42800Y338500D03*
X29000Y338600D03*
X60400Y305900D03*
X60500Y316400D03*
X60300Y331800D03*
X60400Y350300D03*
X44000Y350200D03*
X20100Y350300D03*
X4400D03*
X98000Y68200D03*
X112900Y51800D03*
X102000Y62400D03*
X134800Y60300D03*
X135800Y70800D03*
X140100Y14000D03*
X78838Y11602D03*
X132600Y53800D03*
X96200Y16400D03*
X97500Y36600D03*
X97400Y29300D03*
X133200Y17751D03*
X132600Y29600D03*
X124300Y22600D03*
X107506Y16719D03*
X116430Y16569D03*
X124300Y99500D03*
X97600Y92200D03*
X94193Y99637D03*
X81634Y111544D03*
X76100Y117800D03*
X87600Y106400D03*
X101600Y99700D03*
X135900Y99400D03*
X146700Y108400D03*
X79750Y76600D03*
X79604Y86869D03*
X219300Y-13900D03*
X208500Y-22000D03*
X186200Y14900D03*
X208500Y9400D03*
X203300Y14800D03*
X217800Y14300D03*
X168858Y12000D03*
X218300Y32700D03*
X222609Y53150D03*
X179093Y38185D03*
X163000Y43800D03*
X179500Y42750D03*
X178843Y59000D03*
X188250Y66000D03*
X207293Y45526D03*
X211900Y24800D03*
X194560Y56777D03*
X154700Y116500D03*
X190700Y127400D03*
X184700Y112500D03*
X218700Y132335D03*
X219000Y107560D03*
X214500Y112000D03*
X192691Y84234D03*
X214800Y128309D03*
X186100Y186500D03*
X205848Y199637D03*
X222800Y182000D03*
X199600Y156500D03*
X178747Y288699D03*
X182347Y292152D03*
X199557Y292020D03*
X199521Y288390D03*
X220678Y284412D03*
X191391Y278906D03*
X195939Y278959D03*
X222500Y344500D03*
X200200Y343900D03*
X188300Y343400D03*
X193300Y337900D03*
X211900Y337500D03*
X219900Y330500D03*
X214200Y325100D03*
X209500Y350300D03*
X188000D03*
X172300Y337600D03*
Y350200D03*
X220550Y306050D03*
X224000Y306000D03*
X228400Y-21400D03*
X228600Y42000D03*
X228300Y6100D03*
X228400Y22800D03*
X228600Y69200D03*
Y85900D03*
X227800Y322200D03*
X228500Y337100D03*
X228400Y350200D03*
G54D24*
X217340Y-3360D03*
Y-6960D03*
Y240D03*
Y3840D03*
G54D10*
X-18898Y16741D03*
X-17506Y723144D03*
X13800Y60400D03*
X114497Y137176D03*
X115583Y329366D03*
X114497Y525759D03*
X115583Y717948D03*
X218800Y337200D03*
X365520Y-1413D03*
X366606Y190776D03*
X365520Y387169D03*
X366606Y579359D03*
X494816Y713716D03*
G54D19*
X40157Y211023D03*
X24409D03*
X40157Y261417D03*
X24409D03*
X200394Y211023D03*
X184646D03*
X200394Y261417D03*
X184646D03*
G54D23*
X116339Y78740D03*
G54D15*
X22800Y112600D03*
X41492Y106258D03*
X15007Y163581D03*
G54D20*
X22598Y150420D03*
G54D22*
X42126Y303149D03*
X202363D03*
G54D18*
X28346Y222440D03*
X188583D03*
%LPC*%
G75*
G54D26*
G01X-351984Y-328833D02*
X-383984D01*
G01X-351984Y-344833D02*
Y-424833D01*
G01D02*
X998716D01*
G01X-355984Y-328833D02*
G02I-12000J0D01*
G01X-361134D02*
G02I-6850J0D01*
G01X-367984Y-344833D02*
Y-312833D01*
G01X-351984Y-344833D02*
X998716D01*
G01X-351984Y-380333D02*
X998716D01*
G01X211216Y-344833D02*
Y-424833D01*
G01X348716Y-344833D02*
Y-424833D01*
G01X463716Y-344833D02*
Y-424833D01*
G01X631216Y-344833D02*
Y-424833D01*
G01X801216Y-344833D02*
Y-424833D01*
G01X998716Y-344833D02*
Y-424833D01*
G01X1026716Y-328833D02*
G02I-12000J0D01*
G01X1021566D02*
G02I-6850J0D01*
G01X1014716Y-344833D02*
Y-312833D01*
G01X1030716Y-328833D02*
X998716D01*
G54D27*
G01X-322688Y-405500D02*
X-321814Y-404625D01*
X-321159Y-403167D01*
X-320722Y-401124D01*
X-321159Y-399375D01*
X-322032Y-398208D01*
X-323561Y-397333D01*
X-329456D01*
Y-414833D01*
X-322251D01*
X-320722Y-413667D01*
X-319849Y-411916D01*
X-319412Y-409875D01*
X-319849Y-407833D01*
X-321159Y-406083D01*
X-322688Y-405500D01*
X-329456D01*
G01X-309991Y-414833D02*
Y-403167D01*
G01Y-405500D02*
X-308899Y-404333D01*
X-307807Y-403458D01*
X-306279Y-403167D01*
X-305188Y-403458D01*
X-303877Y-404333D01*
G01X-294019Y-420083D02*
X-292709Y-420666D01*
X-290962Y-420083D01*
X-289871Y-418917D01*
X-288997Y-417458D01*
X-287688Y-412792D01*
X-284849Y-403167D01*
G01X-291836D02*
X-287688Y-412792D01*
G01X-268441Y-404625D02*
X-269969Y-403458D01*
X-271279Y-403167D01*
X-273026Y-403750D01*
X-274336Y-404916D01*
X-275209Y-406958D01*
X-275428Y-409000D01*
X-275209Y-411042D01*
X-274336Y-412792D01*
X-273026Y-414250D01*
X-271279Y-414833D01*
X-269751Y-414250D01*
X-268441Y-413083D01*
G01X-257709Y-406958D02*
X-250722D01*
X-251377Y-404916D01*
X-252469Y-403750D01*
X-253997Y-403167D01*
X-255526Y-403458D01*
X-256836Y-404333D01*
X-257709Y-406375D01*
X-258146Y-408125D01*
Y-409875D01*
X-257709Y-411625D01*
X-256617Y-413375D01*
X-255307Y-414541D01*
X-253779Y-414833D01*
X-252251Y-414250D01*
X-250722Y-412500D01*
G01X-214631Y-398792D02*
X-215941Y-397916D01*
X-217469Y-397333D01*
X-219216D01*
X-221181Y-398208D01*
X-222709Y-399666D01*
X-223801Y-401417D01*
X-224674Y-404333D01*
X-224893Y-406958D01*
X-224456Y-409583D01*
X-223801Y-411333D01*
X-222491Y-413083D01*
X-220962Y-414250D01*
X-219434Y-414833D01*
X-217906D01*
X-216377Y-414250D01*
X-215067Y-413375D01*
X-213975Y-412209D01*
G01X-198004Y-414833D02*
Y-403167D01*
G01Y-405208D02*
X-198877Y-404042D01*
X-200188Y-403458D01*
X-201716Y-403167D01*
X-203244Y-403750D01*
X-204554Y-404916D01*
X-205428Y-406666D01*
X-205864Y-409000D01*
X-205428Y-411333D01*
X-204554Y-413083D01*
X-203244Y-414250D01*
X-201716Y-414833D01*
X-200188Y-414541D01*
X-198877Y-413667D01*
X-198004Y-412500D01*
G01X-188146Y-414833D02*
Y-403167D01*
G01Y-406083D02*
X-187272Y-404625D01*
X-185962Y-403458D01*
X-184216Y-403167D01*
X-182688Y-403458D01*
X-181377Y-404625D01*
X-180722Y-406666D01*
Y-414833D01*
G01X-171519Y-420083D02*
X-170209Y-420666D01*
X-168462Y-420083D01*
X-167371Y-418917D01*
X-166497Y-417458D01*
X-165188Y-412792D01*
X-162349Y-403167D01*
G01X-169336D02*
X-165188Y-412792D01*
G01X-149434Y-414833D02*
X-150744Y-414541D01*
X-152054Y-413375D01*
X-152928Y-411333D01*
X-153364Y-409000D01*
X-152928Y-406666D01*
X-152054Y-404625D01*
X-150744Y-403458D01*
X-149434Y-403167D01*
X-148124Y-403458D01*
X-146814Y-404625D01*
X-145941Y-406666D01*
X-145722Y-409000D01*
X-145941Y-411333D01*
X-146814Y-413375D01*
X-148124Y-414541D01*
X-149434Y-414833D01*
G01X-135646D02*
Y-403167D01*
G01Y-406083D02*
X-134772Y-404625D01*
X-133462Y-403458D01*
X-131716Y-403167D01*
X-130188Y-403458D01*
X-128877Y-404625D01*
X-128222Y-406666D01*
Y-414833D01*
G01X-101082D02*
Y-397333D01*
X-92786D01*
G01X-95842Y-405791D02*
X-101082D01*
G01X-82491Y-414833D02*
Y-403167D01*
G01Y-405500D02*
X-81399Y-404333D01*
X-80307Y-403458D01*
X-78779Y-403167D01*
X-77688Y-403458D01*
X-76377Y-404333D01*
G01X-61934Y-414833D02*
X-63244Y-414541D01*
X-64554Y-413375D01*
X-65428Y-411333D01*
X-65864Y-409000D01*
X-65428Y-406666D01*
X-64554Y-404625D01*
X-63244Y-403458D01*
X-61934Y-403167D01*
X-60624Y-403458D01*
X-59314Y-404625D01*
X-58441Y-406666D01*
X-58222Y-409000D01*
X-58441Y-411333D01*
X-59314Y-413375D01*
X-60624Y-414541D01*
X-61934Y-414833D01*
G01X-48146D02*
Y-403167D01*
G01Y-406083D02*
X-47272Y-404625D01*
X-45962Y-403458D01*
X-44216Y-403167D01*
X-42688Y-403458D01*
X-41377Y-404625D01*
X-40722Y-406666D01*
Y-414833D01*
G01X-26934Y-397333D02*
Y-414833D01*
G01X-29991Y-403167D02*
X-23877D01*
G01X3699Y-414833D02*
Y-397333D01*
X8939D01*
X10686Y-398208D01*
X11996Y-400250D01*
X12433Y-402583D01*
X11996Y-404916D01*
X10904Y-406666D01*
X8939Y-407542D01*
X3699D01*
G01X29496Y-414833D02*
Y-403167D01*
G01Y-405208D02*
X28623Y-404042D01*
X27312Y-403458D01*
X25784Y-403167D01*
X24256Y-403750D01*
X22946Y-404916D01*
X22072Y-406666D01*
X21636Y-409000D01*
X22072Y-411333D01*
X22946Y-413083D01*
X24256Y-414250D01*
X25784Y-414833D01*
X27312Y-414541D01*
X28623Y-413667D01*
X29496Y-412500D01*
G01X39354Y-414833D02*
Y-403167D01*
G01Y-406083D02*
X40228Y-404625D01*
X41538Y-403458D01*
X43284Y-403167D01*
X44812Y-403458D01*
X46123Y-404625D01*
X46778Y-406666D01*
Y-414833D01*
G01X57291Y-406958D02*
X64278D01*
X63623Y-404916D01*
X62531Y-403750D01*
X61003Y-403167D01*
X59474Y-403458D01*
X58164Y-404333D01*
X57291Y-406375D01*
X56854Y-408125D01*
Y-409875D01*
X57291Y-411625D01*
X58383Y-413375D01*
X59693Y-414541D01*
X61221Y-414833D01*
X62749Y-414250D01*
X64278Y-412500D01*
G01X78066Y-414833D02*
Y-397333D01*
G01X114812Y-405500D02*
X115686Y-404625D01*
X116341Y-403167D01*
X116778Y-401124D01*
X116341Y-399375D01*
X115468Y-398208D01*
X113939Y-397333D01*
X108044D01*
Y-414833D01*
X115249D01*
X116778Y-413667D01*
X117651Y-411916D01*
X118088Y-409875D01*
X117651Y-407833D01*
X116341Y-406083D01*
X114812Y-405500D01*
X108044D01*
G01X130566Y-414833D02*
X129256Y-414541D01*
X127946Y-413375D01*
X127072Y-411333D01*
X126636Y-409000D01*
X127072Y-406666D01*
X127946Y-404625D01*
X129256Y-403458D01*
X130566Y-403167D01*
X131876Y-403458D01*
X133186Y-404625D01*
X134059Y-406666D01*
X134278Y-409000D01*
X134059Y-411333D01*
X133186Y-413375D01*
X131876Y-414541D01*
X130566Y-414833D01*
G01X151996D02*
Y-403167D01*
G01Y-405208D02*
X151123Y-404042D01*
X149812Y-403458D01*
X148284Y-403167D01*
X146756Y-403750D01*
X145446Y-404916D01*
X144572Y-406666D01*
X144136Y-409000D01*
X144572Y-411333D01*
X145446Y-413083D01*
X146756Y-414250D01*
X148284Y-414833D01*
X149812Y-414541D01*
X151123Y-413667D01*
X151996Y-412500D01*
G01X162509Y-414833D02*
Y-403167D01*
G01Y-405500D02*
X163601Y-404333D01*
X164693Y-403458D01*
X166221Y-403167D01*
X167312Y-403458D01*
X168623Y-404333D01*
G01X186996Y-397333D02*
Y-414833D01*
G01Y-412209D02*
X186123Y-413667D01*
X184812Y-414541D01*
X183284Y-414833D01*
X181538Y-414250D01*
X180228Y-412792D01*
X179354Y-411042D01*
X179136Y-409000D01*
X179354Y-406958D01*
X180228Y-405208D01*
X181538Y-403750D01*
X183284Y-403167D01*
X184812Y-403458D01*
X185904Y-404042D01*
X186996Y-405208D01*
G01X-111361Y-369833D02*
Y-352333D01*
X-105684Y-366916D01*
X-100007Y-352333D01*
Y-369833D01*
G01X-88184D02*
X-89494Y-369541D01*
X-90804Y-368375D01*
X-91678Y-366333D01*
X-92114Y-364000D01*
X-91678Y-361666D01*
X-90804Y-359625D01*
X-89494Y-358458D01*
X-88184Y-358167D01*
X-86874Y-358458D01*
X-85564Y-359625D01*
X-84691Y-361666D01*
X-84472Y-364000D01*
X-84691Y-366333D01*
X-85564Y-368375D01*
X-86874Y-369541D01*
X-88184Y-369833D01*
G01X-66754Y-352333D02*
Y-369833D01*
G01Y-367209D02*
X-67627Y-368667D01*
X-68938Y-369541D01*
X-70466Y-369833D01*
X-72212Y-369250D01*
X-73522Y-367792D01*
X-74396Y-366042D01*
X-74614Y-364000D01*
X-74396Y-361958D01*
X-73522Y-360208D01*
X-72212Y-358750D01*
X-70466Y-358167D01*
X-68938Y-358458D01*
X-67846Y-359042D01*
X-66754Y-360208D01*
G01X-56459Y-361958D02*
X-49472D01*
X-50127Y-359916D01*
X-51219Y-358750D01*
X-52747Y-358167D01*
X-54276Y-358458D01*
X-55586Y-359333D01*
X-56459Y-361375D01*
X-56896Y-363125D01*
Y-364875D01*
X-56459Y-366625D01*
X-55367Y-368375D01*
X-54057Y-369541D01*
X-52529Y-369833D01*
X-51001Y-369250D01*
X-49472Y-367500D01*
G01X-35684Y-369833D02*
Y-352333D01*
G01X244916Y-414833D02*
Y-397333D01*
X242296Y-400833D01*
G01Y-414833D02*
X247536D01*
G01X258268Y-407542D02*
X259796Y-405500D01*
X261106Y-404333D01*
X262853Y-403750D01*
X264381Y-404333D01*
X265473Y-405500D01*
X266346Y-407250D01*
X266564Y-409291D01*
X266346Y-411042D01*
X265473Y-412792D01*
X264162Y-414250D01*
X262634Y-414833D01*
X260888Y-414250D01*
X259359Y-412500D01*
X258486Y-409875D01*
X258268Y-406958D01*
X258704Y-403167D01*
X259359Y-401124D01*
X260451Y-399083D01*
X261979Y-397625D01*
X263508Y-397333D01*
X265036Y-397916D01*
X266128Y-399375D01*
G01X275113Y-411333D02*
X276422Y-413375D01*
X278169Y-414541D01*
X280134Y-414833D01*
X281881Y-414541D01*
X283628Y-413083D01*
X284719Y-411333D01*
X284938Y-409583D01*
X284501Y-407542D01*
X282973Y-406083D01*
X281444Y-405500D01*
X279479D01*
G01X281444D02*
X282754Y-404625D01*
X283846Y-403167D01*
X284283Y-401417D01*
X283846Y-399666D01*
X282754Y-398208D01*
X280789Y-397333D01*
X278824Y-397625D01*
X276859Y-398792D01*
G01X293268Y-407542D02*
X294796Y-405500D01*
X296106Y-404333D01*
X297853Y-403750D01*
X299381Y-404333D01*
X300473Y-405500D01*
X301346Y-407250D01*
X301564Y-409291D01*
X301346Y-411042D01*
X300473Y-412792D01*
X299162Y-414250D01*
X297634Y-414833D01*
X295888Y-414250D01*
X294359Y-412500D01*
X293486Y-409875D01*
X293268Y-406958D01*
X293704Y-403167D01*
X294359Y-401124D01*
X295451Y-399083D01*
X296979Y-397625D01*
X298508Y-397333D01*
X300036Y-397916D01*
X301128Y-399375D01*
G01X311204Y-412792D02*
X312733Y-414250D01*
X314479Y-414833D01*
X316226Y-414250D01*
X317754Y-412500D01*
X318846Y-409875D01*
X319283Y-407250D01*
Y-404042D01*
X318846Y-401417D01*
X317754Y-399083D01*
X316444Y-397916D01*
X314916Y-397333D01*
X313169Y-397916D01*
X311859Y-399083D01*
X310986Y-400833D01*
X310549Y-403167D01*
X310986Y-405208D01*
X312078Y-407250D01*
X313388Y-408417D01*
X314916Y-408708D01*
X316662Y-408125D01*
X317973Y-406666D01*
X319283Y-404042D01*
G01X231799Y-369833D02*
Y-352333D01*
X237039D01*
X238786Y-353208D01*
X240096Y-355250D01*
X240533Y-357583D01*
X240096Y-359916D01*
X239004Y-361666D01*
X237039Y-362542D01*
X231799D01*
G01X258469Y-353792D02*
X257159Y-352916D01*
X255631Y-352333D01*
X253884D01*
X251919Y-353208D01*
X250391Y-354666D01*
X249299Y-356417D01*
X248426Y-359333D01*
X248207Y-361958D01*
X248644Y-364583D01*
X249299Y-366333D01*
X250609Y-368083D01*
X252138Y-369250D01*
X253666Y-369833D01*
X255194D01*
X256723Y-369250D01*
X258033Y-368375D01*
X259125Y-367209D01*
G01X272912Y-360500D02*
X273786Y-359625D01*
X274441Y-358167D01*
X274878Y-356124D01*
X274441Y-354375D01*
X273568Y-353208D01*
X272039Y-352333D01*
X266144D01*
Y-369833D01*
X273349D01*
X274878Y-368667D01*
X275751Y-366916D01*
X276188Y-364875D01*
X275751Y-362833D01*
X274441Y-361083D01*
X272912Y-360500D01*
X266144D01*
G01X282116Y-375666D02*
X295216D01*
G01X301144Y-369833D02*
Y-352333D01*
X311188Y-369833D01*
Y-352333D01*
G01X323666Y-369833D02*
X321919Y-369541D01*
X320391Y-368375D01*
X319081Y-366625D01*
X318207Y-364583D01*
X317771Y-362250D01*
Y-359916D01*
X318207Y-357583D01*
X319081Y-355541D01*
X320391Y-353792D01*
X321919Y-352625D01*
X323666Y-352333D01*
X325412Y-352625D01*
X326941Y-353792D01*
X328251Y-355541D01*
X329125Y-357583D01*
X329561Y-359916D01*
Y-362250D01*
X329125Y-364583D01*
X328251Y-366625D01*
X326941Y-368375D01*
X325412Y-369541D01*
X323666Y-369833D01*
G01X374507Y-352333D02*
X379966Y-369833D01*
X385425Y-352333D01*
G01X401833Y-369833D02*
X393099D01*
Y-352333D01*
X401833D01*
G01X398339Y-360791D02*
X393099D01*
G01X410599Y-369833D02*
Y-352333D01*
X416058D01*
X417804Y-353208D01*
X418896Y-354375D01*
X419333Y-356708D01*
X418896Y-359042D01*
X417586Y-360500D01*
X416058Y-361375D01*
X410599D01*
G01X416058D02*
X419333Y-369833D01*
G01X432466Y-370416D02*
X432029Y-370125D01*
Y-369541D01*
X432466Y-369250D01*
X432903Y-369541D01*
Y-370125D01*
X432466Y-370416D01*
G01X392881Y-412500D02*
X394628Y-413958D01*
X396593Y-414833D01*
X398339D01*
X400086Y-413958D01*
X401396Y-412500D01*
X402051Y-410458D01*
X401614Y-408417D01*
X400523Y-406666D01*
X398558Y-405500D01*
X395938Y-404916D01*
X394409Y-403750D01*
X393754Y-401708D01*
X394191Y-399666D01*
X395283Y-398208D01*
X396811Y-397333D01*
X398339D01*
X399868Y-397916D01*
X401178Y-399375D01*
G01X410163Y-414833D02*
Y-397333D01*
X414529D01*
X416276Y-398208D01*
X417586Y-399375D01*
X418678Y-401124D01*
X419551Y-403167D01*
X419769Y-406083D01*
X419551Y-409000D01*
X418678Y-411042D01*
X417586Y-412792D01*
X416276Y-413958D01*
X414529Y-414833D01*
X410163D01*
G01X586783Y-397333D02*
Y-414833D01*
X578049D01*
G01X569719Y-411333D02*
X568410Y-413375D01*
X566663Y-414541D01*
X564698Y-414833D01*
X562951Y-414541D01*
X561204Y-413083D01*
X560113Y-411333D01*
X559894Y-409583D01*
X560331Y-407542D01*
X561859Y-406083D01*
X563388Y-405500D01*
X565353D01*
G01X563388D02*
X562078Y-404625D01*
X560986Y-403167D01*
X560549Y-401417D01*
X560986Y-399666D01*
X562078Y-398208D01*
X564043Y-397333D01*
X566008Y-397625D01*
X567973Y-398792D01*
G01X552875Y-397333D02*
X547416Y-414833D01*
X541957Y-397333D01*
G01X525113Y-398792D02*
X526423Y-397916D01*
X527951Y-397333D01*
X529698D01*
X531663Y-398208D01*
X533191Y-399666D01*
X534283Y-401417D01*
X535156Y-404333D01*
X535375Y-406958D01*
X534938Y-409583D01*
X534283Y-411333D01*
X532973Y-413083D01*
X531444Y-414250D01*
X529916Y-414833D01*
X528388D01*
X526859Y-414250D01*
X525549Y-413375D01*
X524457Y-412209D01*
G01X507613Y-398792D02*
X508923Y-397916D01*
X510451Y-397333D01*
X512198D01*
X514163Y-398208D01*
X515691Y-399666D01*
X516783Y-401417D01*
X517656Y-404333D01*
X517875Y-406958D01*
X517438Y-409583D01*
X516783Y-411333D01*
X515473Y-413083D01*
X513944Y-414250D01*
X512416Y-414833D01*
X510888D01*
X509359Y-414250D01*
X508049Y-413375D01*
X506957Y-412209D01*
G01X508049Y-352333D02*
Y-369833D01*
X516783D01*
G01X533846D02*
Y-358167D01*
G01Y-360208D02*
X532973Y-359042D01*
X531662Y-358458D01*
X530134Y-358167D01*
X528606Y-358750D01*
X527296Y-359916D01*
X526422Y-361666D01*
X525986Y-364000D01*
X526422Y-366333D01*
X527296Y-368083D01*
X528606Y-369250D01*
X530134Y-369833D01*
X531662Y-369541D01*
X532973Y-368667D01*
X533846Y-367500D01*
G01X542831Y-375083D02*
X544141Y-375666D01*
X545888Y-375083D01*
X546979Y-373917D01*
X547853Y-372458D01*
X549162Y-367792D01*
X552001Y-358167D01*
G01X545014D02*
X549162Y-367792D01*
G01X561641Y-361958D02*
X568628D01*
X567973Y-359916D01*
X566881Y-358750D01*
X565353Y-358167D01*
X563824Y-358458D01*
X562514Y-359333D01*
X561641Y-361375D01*
X561204Y-363125D01*
Y-364875D01*
X561641Y-366625D01*
X562733Y-368375D01*
X564043Y-369541D01*
X565571Y-369833D01*
X567099Y-369250D01*
X568628Y-367500D01*
G01X579359Y-369833D02*
Y-358167D01*
G01Y-360500D02*
X580451Y-359333D01*
X581543Y-358458D01*
X583071Y-358167D01*
X584162Y-358458D01*
X585473Y-359333D01*
G01X672466Y-414833D02*
X670719Y-414541D01*
X669191Y-413375D01*
X667881Y-411625D01*
X667007Y-409583D01*
X666571Y-407250D01*
Y-404916D01*
X667007Y-402583D01*
X667881Y-400541D01*
X669191Y-398792D01*
X670719Y-397625D01*
X672466Y-397333D01*
X674212Y-397625D01*
X675741Y-398792D01*
X677051Y-400541D01*
X677925Y-402583D01*
X678361Y-404916D01*
Y-407250D01*
X677925Y-409583D01*
X677051Y-411625D01*
X675741Y-413375D01*
X674212Y-414541D01*
X672466Y-414833D01*
G01X674212Y-410166D02*
X676833Y-414833D01*
G01X685163Y-397333D02*
Y-409875D01*
X686036Y-412500D01*
X687783Y-414250D01*
X689966Y-414833D01*
X692149Y-414250D01*
X693896Y-412500D01*
X694769Y-409875D01*
Y-397333D01*
G01X704846D02*
X710086D01*
G01X707466D02*
Y-414833D01*
G01X704846D02*
X710086D01*
G01X719944D02*
Y-397333D01*
X729988Y-414833D01*
Y-397333D01*
G01X747269Y-398792D02*
X745959Y-397916D01*
X744431Y-397333D01*
X742684D01*
X740719Y-398208D01*
X739191Y-399666D01*
X738099Y-401417D01*
X737226Y-404333D01*
X737007Y-406958D01*
X737444Y-409583D01*
X738099Y-411333D01*
X739409Y-413083D01*
X740938Y-414250D01*
X742466Y-414833D01*
X743994D01*
X745523Y-414250D01*
X746833Y-413375D01*
X747925Y-412209D01*
G01X759966Y-414833D02*
Y-406958D01*
X755599Y-397333D01*
G01X764333D02*
X759966Y-406958D01*
G01X650163Y-369833D02*
Y-352333D01*
X654529D01*
X656276Y-353208D01*
X657586Y-354375D01*
X658678Y-356124D01*
X659551Y-358167D01*
X659769Y-361083D01*
X659551Y-364000D01*
X658678Y-366042D01*
X657586Y-367792D01*
X656276Y-368958D01*
X654529Y-369833D01*
X650163D01*
G01X669191Y-361958D02*
X676178D01*
X675523Y-359916D01*
X674431Y-358750D01*
X672903Y-358167D01*
X671374Y-358458D01*
X670064Y-359333D01*
X669191Y-361375D01*
X668754Y-363125D01*
Y-364875D01*
X669191Y-366625D01*
X670283Y-368375D01*
X671593Y-369541D01*
X673121Y-369833D01*
X674649Y-369250D01*
X676178Y-367500D01*
G01X686691Y-367792D02*
X687783Y-368958D01*
X689311Y-369833D01*
X690621D01*
X691931Y-369250D01*
X692804Y-368375D01*
X693241Y-367209D01*
X693023Y-365458D01*
X692149Y-364583D01*
X688219Y-362833D01*
X687346Y-360791D01*
X687783Y-359333D01*
X688656Y-358458D01*
X689966Y-358167D01*
X691276Y-358458D01*
X692586Y-359333D01*
G01X707466Y-358167D02*
Y-369833D01*
G01Y-353500D02*
X707029Y-353208D01*
Y-352625D01*
X707466Y-352333D01*
X707903Y-352625D01*
Y-353208D01*
X707466Y-353500D01*
G01X721909Y-374208D02*
X723438Y-375375D01*
X725184Y-375666D01*
X726712Y-375375D01*
X728023Y-373917D01*
X728896Y-371875D01*
Y-358167D01*
G01Y-360500D02*
X728023Y-359333D01*
X726712Y-358458D01*
X725184Y-358167D01*
X723438Y-358750D01*
X722346Y-359916D01*
X721472Y-361958D01*
X721036Y-364000D01*
X721254Y-365750D01*
X722128Y-367792D01*
X723438Y-369250D01*
X725184Y-369833D01*
X726494Y-369541D01*
X728023Y-368375D01*
X728896Y-367209D01*
G01X738754Y-369833D02*
Y-358167D01*
G01Y-361083D02*
X739628Y-359625D01*
X740938Y-358458D01*
X742684Y-358167D01*
X744212Y-358458D01*
X745523Y-359625D01*
X746178Y-361666D01*
Y-369833D01*
G01X756691Y-361958D02*
X763678D01*
X763023Y-359916D01*
X761931Y-358750D01*
X760403Y-358167D01*
X758874Y-358458D01*
X757564Y-359333D01*
X756691Y-361375D01*
X756254Y-363125D01*
Y-364875D01*
X756691Y-366625D01*
X757783Y-368375D01*
X759093Y-369541D01*
X760621Y-369833D01*
X762149Y-369250D01*
X763678Y-367500D01*
G01X774409Y-369833D02*
Y-358167D01*
G01Y-360500D02*
X775501Y-359333D01*
X776593Y-358458D01*
X778121Y-358167D01*
X779212Y-358458D01*
X780523Y-359333D01*
G01X821166Y-397333D02*
X819419Y-397916D01*
X818109Y-399375D01*
X817236Y-401124D01*
X816581Y-403458D01*
X816363Y-406083D01*
X816581Y-408708D01*
X817236Y-411042D01*
X818109Y-412792D01*
X819419Y-414250D01*
X821166Y-414833D01*
X822912Y-414250D01*
X824223Y-412792D01*
X825096Y-411042D01*
X825751Y-408708D01*
X825969Y-406083D01*
X825751Y-403458D01*
X825096Y-401124D01*
X824223Y-399375D01*
X822912Y-397916D01*
X821166Y-397333D01*
G01X833863Y-411333D02*
X835172Y-413375D01*
X836919Y-414541D01*
X838884Y-414833D01*
X840631Y-414541D01*
X842378Y-413083D01*
X843469Y-411333D01*
X843688Y-409583D01*
X843251Y-407542D01*
X841723Y-406083D01*
X840194Y-405500D01*
X838229D01*
G01X840194D02*
X841504Y-404625D01*
X842596Y-403167D01*
X843033Y-401417D01*
X842596Y-399666D01*
X841504Y-398208D01*
X839539Y-397333D01*
X837574Y-397625D01*
X835609Y-398792D01*
G01X852236Y-415416D02*
X860096Y-397333D01*
G01X869518Y-400250D02*
X870828Y-398500D01*
X872356Y-397625D01*
X874103Y-397333D01*
X876286Y-397916D01*
X877814Y-399375D01*
X878251Y-401124D01*
X878033Y-402875D01*
X877159Y-404333D01*
X872793Y-407250D01*
X870828Y-409291D01*
X869518Y-412209D01*
X869081Y-414833D01*
X878251D01*
G01X887454Y-412792D02*
X888983Y-414250D01*
X890729Y-414833D01*
X892476Y-414250D01*
X894004Y-412500D01*
X895096Y-409875D01*
X895533Y-407250D01*
Y-404042D01*
X895096Y-401417D01*
X894004Y-399083D01*
X892694Y-397916D01*
X891166Y-397333D01*
X889419Y-397916D01*
X888109Y-399083D01*
X887236Y-400833D01*
X886799Y-403167D01*
X887236Y-405208D01*
X888328Y-407250D01*
X889638Y-408417D01*
X891166Y-408708D01*
X892912Y-408125D01*
X894223Y-406666D01*
X895533Y-404042D01*
G01X904736Y-415416D02*
X912596Y-397333D01*
G01X922018Y-400250D02*
X923328Y-398500D01*
X924856Y-397625D01*
X926603Y-397333D01*
X928786Y-397916D01*
X930314Y-399375D01*
X930751Y-401124D01*
X930533Y-402875D01*
X929659Y-404333D01*
X925293Y-407250D01*
X923328Y-409291D01*
X922018Y-412209D01*
X921581Y-414833D01*
X930751D01*
G01X943666Y-397333D02*
X941919Y-397916D01*
X940609Y-399375D01*
X939736Y-401124D01*
X939081Y-403458D01*
X938863Y-406083D01*
X939081Y-408708D01*
X939736Y-411042D01*
X940609Y-412792D01*
X941919Y-414250D01*
X943666Y-414833D01*
X945412Y-414250D01*
X946723Y-412792D01*
X947596Y-411042D01*
X948251Y-408708D01*
X948469Y-406083D01*
X948251Y-403458D01*
X947596Y-401124D01*
X946723Y-399375D01*
X945412Y-397916D01*
X943666Y-397333D01*
G01X961166Y-414833D02*
Y-397333D01*
X958546Y-400833D01*
G01Y-414833D02*
X963786D01*
G01X978229D02*
X978666Y-411042D01*
X979321Y-407833D01*
X980194Y-404916D01*
X981286Y-401708D01*
X983033Y-397333D01*
X974299D01*
G01X868863Y-369833D02*
Y-352333D01*
X873229D01*
X874976Y-353208D01*
X876286Y-354375D01*
X877378Y-356124D01*
X878251Y-358167D01*
X878469Y-361083D01*
X878251Y-364000D01*
X877378Y-366042D01*
X876286Y-367792D01*
X874976Y-368958D01*
X873229Y-369833D01*
X868863D01*
G01X895096D02*
Y-358167D01*
G01Y-360208D02*
X894223Y-359042D01*
X892912Y-358458D01*
X891384Y-358167D01*
X889856Y-358750D01*
X888546Y-359916D01*
X887672Y-361666D01*
X887236Y-364000D01*
X887672Y-366333D01*
X888546Y-368083D01*
X889856Y-369250D01*
X891384Y-369833D01*
X892912Y-369541D01*
X894223Y-368667D01*
X895096Y-367500D01*
G01X908666Y-352333D02*
Y-369833D01*
G01X905609Y-358167D02*
X911723D01*
G01X922891Y-361958D02*
X929878D01*
X929223Y-359916D01*
X928131Y-358750D01*
X926603Y-358167D01*
X925074Y-358458D01*
X923764Y-359333D01*
X922891Y-361375D01*
X922454Y-363125D01*
Y-364875D01*
X922891Y-366625D01*
X923983Y-368375D01*
X925293Y-369541D01*
X926821Y-369833D01*
X928349Y-369250D01*
X929878Y-367500D01*
M02*
